(kicad_pcb
	(version 20260206)
	(generator "pcbnew")
	(generator_version "10.0")
	(general
		(thickness 1.6)
		(legacy_teardrops no)
	)
	(paper "A4")
	(title_block
		(title "Bryce Canyon_IOM_IOC_16318-2_OCP.brd")
		(comment 1 "Bryce Canyon / footprints 509-517 of 1605")
	)
	(layers
		(0 "F.Cu" signal "TOP")
		(4 "In1.Cu" signal "L2GND")
		(6 "In2.Cu" signal "L3")
		(8 "In3.Cu" signal "L4VCC")
		(10 "In4.Cu" signal "L5VCC")
		(12 "In5.Cu" signal "L6")
		(14 "In6.Cu" signal "L7GND")
		(2 "B.Cu" signal "BOTTOM")
		(9 "F.Adhes" user "F.Adhesive")
		(11 "B.Adhes" user "B.Adhesive")
		(13 "F.Paste" user "Package Geometry/Pastemask Top")
		(15 "B.Paste" user "Package Geometry/Pastemask Bottom")
		(5 "F.SilkS" user "Ref Des/Silkscreen Top")
		(7 "B.SilkS" user "Ref Des/Silkscreen Bottom")
		(1 "F.Mask" user "Board Geometry/Soldermask Top")
		(3 "B.Mask" user "Board Geometry/Soldermask Bottom")
		(17 "Dwgs.User" user "User.Drawings")
		(19 "Cmts.User" user "User.Comments")
		(21 "Eco1.User" user "User.Eco1")
		(23 "Eco2.User" user "User.Eco2")
		(25 "Edge.Cuts" user "Board Geometry/Outline")
		(27 "Margin" user)
		(31 "F.CrtYd" user "Package Geometry/Place Bound Top")
		(29 "B.CrtYd" user "Package Geometry/Place Bound Bottom")
		(35 "F.Fab" user "Ref Des/Assembly Top")
		(33 "B.Fab" user "Ref Des/Assembly Bottom")
	)
	(footprint ""
		(layer "F.Cu")
		(at 77.283818 -74.153268 90)
		(property "Reference" "VIA2"
			(at 0 0 90)
			(layer "F.SilkS")
			(hide yes)
			(effects
				(font
					(size 1.27 1.27)
				)
			)
		)
		(property "Value" "85OHM-8L-1D6MM-L16L18-GP"
			(at 4.064 0.6096 90)
			(unlocked yes)
			(layer "F.Fab")
			(hide yes)
			(effects
				(font
					(size 1.016 1.016)
					(thickness 0.1524)
				)
			)
		)
		(property "Device Type" "VIA-PCIE-4P-368076"
			(at 4.064 -0.9144 90)
			(unlocked yes)
			(layer "F.Fab")
			(hide yes)
			(effects
				(font
					(size 1.016 1.016)
					(thickness 0.1524)
				)
			)
		)
		(duplicate_pad_numbers_are_jumpers no)
		(fp_rect
			(start -1.8415 0.381)
			(end 1.8415 -0.381)
			(stroke
				(width 0)
				(type default)
			)
			(fill no)
			(layer "F.CrtYd")
		)
		(fp_rect
			(start -1.8415 0.381)
			(end 1.8415 -0.381)
			(stroke
				(width 0)
				(type default)
			)
			(fill no)
			(layer "F.Fab")
		)
		(pad "1" thru_hole circle
			(at -1.4605 0 90)
			(size 0.508 0.508)
			(drill 0.254)
			(layers "*.Cu" "*.Mask")
			(remove_unused_layers no)
			(net "GND")
			(clearance 0.127)
			(thermal_gap 0.127)
		)
		(pad "2" thru_hole circle
			(at -0.4445 0 90)
			(size 0.508 0.508)
			(drill 0.254)
			(layers "*.Cu" "*.Mask")
			(remove_unused_layers no)
			(net "PCIE_COMP_TO_IOM_17_DP")
			(clearance 0.127)
			(thermal_gap 0.127)
		)
		(pad "3" thru_hole circle
			(at 0.4445 0 90)
			(size 0.508 0.508)
			(drill 0.254)
			(layers "*.Cu" "*.Mask")
			(remove_unused_layers no)
			(net "PCIE_COMP_TO_IOM_17_DN")
			(clearance 0.127)
			(thermal_gap 0.127)
		)
		(pad "4" thru_hole circle
			(at 1.4605 0 90)
			(size 0.508 0.508)
			(drill 0.254)
			(layers "*.Cu" "*.Mask")
			(remove_unused_layers no)
			(net "GND")
			(clearance 0.127)
			(thermal_gap 0.127)
		)
	)
	(footprint ""
		(layer "F.Cu")
		(at 168.6306 -109.1946 -90)
		(property "Reference" "C466"
			(at 0 0 270)
			(layer "F.SilkS")
			(hide yes)
			(effects
				(font
					(size 1.27 1.27)
				)
			)
		)
		(property "Value" "SC1U16V2KX-7-GP"
			(at 1.7526 -1.6002 270)
			(unlocked yes)
			(layer "F.Fab")
			(hide yes)
			(effects
				(font
					(size 1.016 1.016)
					(thickness 0.1524)
				)
			)
		)
		(property "Device Type" "C402-TO0D2H24"
			(at 1.7526 -3.1242 270)
			(unlocked yes)
			(layer "F.Fab")
			(hide yes)
			(effects
				(font
					(size 1.016 1.016)
					(thickness 0.1524)
				)
			)
		)
		(duplicate_pad_numbers_are_jumpers no)
		(fp_rect
			(start -0.4826 0.889)
			(end 0.4826 -0.889)
			(stroke
				(width 0)
				(type default)
			)
			(fill no)
			(layer "F.CrtYd")
		)
		(fp_rect
			(start -0.4826 0.889)
			(end 0.4826 -0.889)
			(stroke
				(width 0)
				(type default)
			)
			(fill no)
			(layer "F.Fab")
		)
		(pad "1" smd custom
			(at 0 -0.4572 270)
			(size 0.1524 0.1524)
			(layers "F.Cu" "F.Mask" "F.Paste")
			(net "P1V8")
			(options
				(clearance outline)
				(anchor circle)
			)
			(primitives
				(gr_poly
					(pts
						(arc
							(start -0.254 0.3048)
							(mid -0.325842 0.275042)
							(end -0.3556 0.2032)
						)
						(arc
							(start -0.3556 -0.2032)
							(mid -0.325842 -0.275042)
							(end -0.254 -0.3048)
						)
						(arc
							(start 0.254 -0.3048)
							(mid 0.325842 -0.275042)
							(end 0.3556 -0.2032)
						)
						(arc
							(start 0.3556 0.2032)
							(mid 0.325842 0.275042)
							(end 0.254 0.3048)
						)
					)
					(width 0)
					(fill yes)
				)
			)
		)
		(pad "2" smd custom
			(at 0 0.4572 270)
			(size 0.1524 0.1524)
			(layers "F.Cu" "F.Mask" "F.Paste")
			(net "GND")
			(options
				(clearance outline)
				(anchor circle)
			)
			(primitives
				(gr_poly
					(pts
						(arc
							(start -0.254 0.3048)
							(mid -0.325842 0.275042)
							(end -0.3556 0.2032)
						)
						(arc
							(start -0.3556 -0.2032)
							(mid -0.325842 -0.275042)
							(end -0.254 -0.3048)
						)
						(arc
							(start 0.254 -0.3048)
							(mid 0.325842 -0.275042)
							(end 0.3556 -0.2032)
						)
						(arc
							(start 0.3556 0.2032)
							(mid 0.325842 0.275042)
							(end 0.254 0.3048)
						)
					)
					(width 0)
					(fill yes)
				)
			)
		)
	)
	(footprint ""
		(layer "F.Cu")
		(at 42.5704 -185.039 90)
		(property "Reference" "L9"
			(at 0 0 90)
			(layer "F.SilkS")
			(hide yes)
			(effects
				(font
					(size 1.27 1.27)
				)
			)
		)
		(property "Value" "COIL-3D3UH-26-GP"
			(at -4.699 -4.0132 90)
			(unlocked yes)
			(layer "F.Fab")
			(hide yes)
			(effects
				(font
					(size 1.016 1.016)
					(thickness 0.1524)
				)
			)
		)
		(property "Device Type" "L7066-1830-UH119"
			(at -4.699 -5.5372 90)
			(unlocked yes)
			(layer "F.Fab")
			(hide yes)
			(effects
				(font
					(size 1.016 1.016)
					(thickness 0.1524)
				)
			)
		)
		(duplicate_pad_numbers_are_jumpers no)
		(fp_line
			(start 3.556 -4.4958)
			(end 3.556 4.4958)
			(stroke
				(width 0.1524)
				(type default)
			)
			(layer "F.SilkS")
		)
		(fp_line
			(start -3.556 -4.4958)
			(end 3.556 -4.4958)
			(stroke
				(width 0.1524)
				(type default)
			)
			(layer "F.SilkS")
		)
		(fp_line
			(start 3.556 4.4958)
			(end -3.556 4.4958)
			(stroke
				(width 0.1524)
				(type default)
			)
			(layer "F.SilkS")
		)
		(fp_line
			(start -3.556 4.4958)
			(end -3.556 -4.4958)
			(stroke
				(width 0.1524)
				(type default)
			)
			(layer "F.SilkS")
		)
		(fp_rect
			(start -3.302 3.4798)
			(end 3.302 -3.4798)
			(stroke
				(width 0)
				(type default)
			)
			(fill no)
			(layer "F.CrtYd")
		)
		(fp_poly
			(pts
				(xy -3.81 4.572) (xy -3.81 -4.572) (xy 3.81 -4.572) (xy 3.81 -0.5588) (xy 3.302 -0.5588) (xy 3.302 -3.4798)
				(xy -3.302 -3.4798) (xy -3.302 3.4798) (xy 3.302 3.4798) (xy 3.302 -0.5461) (xy 3.81 -0.5461) (xy 3.81 4.572)
			)
			(stroke
				(width 0)
				(type default)
			)
			(fill no)
			(layer "F.CrtYd")
		)
		(fp_rect
			(start -3.81 4.572)
			(end 3.81 -4.572)
			(stroke
				(width 0)
				(type default)
			)
			(fill no)
			(layer "F.Fab")
		)
		(pad "1" smd rect
			(at 0 -2.779522 90)
			(size 3.5052 2.921)
			(layers "F.Cu" "F.Mask" "F.Paste")
			(net "P3V3_STBY_LL")
		)
		(pad "2" smd rect
			(at 0 2.779522 90)
			(size 3.5052 2.921)
			(layers "F.Cu" "F.Mask" "F.Paste")
			(net "P3V3_STBY_OUT")
		)
	)
	(footprint ""
		(layer "F.Cu")
		(at 43.2054 -179.4256)
		(property "Reference" "C181"
			(at 0 0 0)
			(layer "F.SilkS")
			(hide yes)
			(effects
				(font
					(size 1.27 1.27)
				)
			)
		)
		(property "Value" "SCD1U25V2KX-2-GP"
			(at 1.1811 -2.7051 0)
			(unlocked yes)
			(layer "F.Fab")
			(hide yes)
			(effects
				(font
					(size 1.016 1.016)
					(thickness 0.1524)
				)
			)
		)
		(property "Device Type" "C402H22"
			(at 1.1811 -4.2291 0)
			(unlocked yes)
			(layer "F.Fab")
			(hide yes)
			(effects
				(font
					(size 1.016 1.016)
					(thickness 0.1524)
				)
			)
		)
		(duplicate_pad_numbers_are_jumpers no)
		(fp_rect
			(start -0.4318 0.9525)
			(end 0.4318 -0.9525)
			(stroke
				(width 0)
				(type default)
			)
			(fill no)
			(layer "F.CrtYd")
		)
		(fp_rect
			(start -0.4318 0.9525)
			(end 0.4318 -0.9525)
			(stroke
				(width 0)
				(type default)
			)
			(fill no)
			(layer "F.Fab")
		)
		(pad "1" smd custom
			(at 0 -0.4445)
			(size 0.1524 0.1524)
			(layers "F.Cu" "F.Mask" "F.Paste")
			(net "P3V3_STBY_OUT")
			(options
				(clearance outline)
				(anchor circle)
			)
			(primitives
				(gr_poly
					(pts
						(arc
							(start 0.3048 -0.2032)
							(mid 0.275042 -0.275042)
							(end 0.2032 -0.3048)
						)
						(arc
							(start -0.2032 -0.3048)
							(mid -0.275042 -0.275042)
							(end -0.3048 -0.2032)
						)
						(arc
							(start -0.3048 0.2032)
							(mid -0.275042 0.275042)
							(end -0.2032 0.3048)
						)
						(arc
							(start 0.2032 0.3048)
							(mid 0.275042 0.275042)
							(end 0.3048 0.2032)
						)
					)
					(width 0)
					(fill yes)
				)
			)
		)
		(pad "2" smd custom
			(at 0 0.4445)
			(size 0.1524 0.1524)
			(layers "F.Cu" "F.Mask" "F.Paste")
			(net "P3V3_STBY_LL_R")
			(options
				(clearance outline)
				(anchor circle)
			)
			(primitives
				(gr_poly
					(pts
						(arc
							(start 0.3048 -0.2032)
							(mid 0.275042 -0.275042)
							(end 0.2032 -0.3048)
						)
						(arc
							(start -0.2032 -0.3048)
							(mid -0.275042 -0.275042)
							(end -0.3048 -0.2032)
						)
						(arc
							(start -0.3048 0.2032)
							(mid -0.275042 0.275042)
							(end -0.2032 0.3048)
						)
						(arc
							(start 0.2032 0.3048)
							(mid 0.275042 0.275042)
							(end 0.3048 0.2032)
						)
					)
					(width 0)
					(fill yes)
				)
			)
		)
	)
	(footprint ""
		(layer "F.Cu")
		(at 211.6328 -65.9638 -45)
		(property "Reference" "VIA47"
			(at 0 0 315)
			(layer "F.SilkS")
			(hide yes)
			(effects
				(font
					(size 1.27 1.27)
				)
			)
		)
		(property "Value" "100OHM-8L-1D6MM-L18L16-GP"
			(at -3.720879 -4.508552 315)
			(unlocked yes)
			(layer "F.Fab")
			(hide yes)
			(effects
				(font
					(size 1.016 1.016)
					(thickness 0.1524)
				)
			)
		)
		(property "Device Type" "VIA-PCIE-4P-394076"
			(at -3.721059 -6.032502 315)
			(unlocked yes)
			(layer "F.Fab")
			(hide yes)
			(effects
				(font
					(size 1.016 1.016)
					(thickness 0.1524)
				)
			)
		)
		(duplicate_pad_numbers_are_jumpers no)
		(fp_poly
			(pts
				(xy -1.968472 -0.380877) (xy 1.968528 -0.380878) (xy 1.968527 0.381122) (xy -1.968472 0.381122)
			)
			(stroke
				(width 0)
				(type default)
			)
			(fill no)
			(layer "F.CrtYd")
		)
		(fp_poly
			(pts
				(xy -1.968472 -0.380877) (xy 1.968528 -0.380878) (xy 1.968527 0.381122) (xy -1.968472 0.381122)
			)
			(stroke
				(width 0)
				(type default)
			)
			(fill no)
			(layer "F.Fab")
		)
		(pad "1" thru_hole circle
			(at -1.5875 0 315)
			(size 0.508 0.508)
			(drill 0.254)
			(layers "*.Cu" "*.Mask")
			(remove_unused_layers no)
			(net "GND")
			(clearance 0.127)
			(thermal_gap 0.127)
		)
		(pad "2" thru_hole circle
			(at -0.571501 0 315)
			(size 0.508 0.508)
			(drill 0.254)
			(layers "*.Cu" "*.Mask")
			(remove_unused_layers no)
			(net "PHY_IOC_TO_CON_B_2_DP")
			(clearance 0.127)
			(thermal_gap 0.127)
		)
		(pad "3" thru_hole circle
			(at 0.571501 0 315)
			(size 0.508 0.508)
			(drill 0.254)
			(layers "*.Cu" "*.Mask")
			(remove_unused_layers no)
			(net "PHY_IOC_TO_CON_B_2_DN")
			(clearance 0.127)
			(thermal_gap 0.127)
		)
		(pad "4" thru_hole circle
			(at 1.5875 0 315)
			(size 0.508 0.508)
			(drill 0.254)
			(layers "*.Cu" "*.Mask")
			(remove_unused_layers no)
			(net "GND")
			(clearance 0.127)
			(thermal_gap 0.127)
		)
	)
	(footprint ""
		(layer "F.Cu")
		(at 201.803 -126.8476)
		(property "Reference" "C252"
			(at 0 0 0)
			(layer "F.SilkS")
			(hide yes)
			(effects
				(font
					(size 1.27 1.27)
				)
			)
		)
		(property "Value" "SC470P50V2KX-3GP"
			(at 1.1811 -2.7051 0)
			(unlocked yes)
			(layer "F.Fab")
			(hide yes)
			(effects
				(font
					(size 1.016 1.016)
					(thickness 0.1524)
				)
			)
		)
		(property "Device Type" "C402H22"
			(at 1.1811 -4.2291 0)
			(unlocked yes)
			(layer "F.Fab")
			(hide yes)
			(effects
				(font
					(size 1.016 1.016)
					(thickness 0.1524)
				)
			)
		)
		(duplicate_pad_numbers_are_jumpers no)
		(fp_rect
			(start -0.4318 0.9525)
			(end 0.4318 -0.9525)
			(stroke
				(width 0)
				(type default)
			)
			(fill no)
			(layer "F.CrtYd")
		)
		(fp_rect
			(start -0.4318 0.9525)
			(end 0.4318 -0.9525)
			(stroke
				(width 0)
				(type default)
			)
			(fill no)
			(layer "F.Fab")
		)
		(pad "1" smd custom
			(at 0 -0.4445)
			(size 0.1524 0.1524)
			(layers "F.Cu" "F.Mask" "F.Paste")
			(net "GND")
			(options
				(clearance outline)
				(anchor circle)
			)
			(primitives
				(gr_poly
					(pts
						(arc
							(start 0.3048 -0.2032)
							(mid 0.275042 -0.275042)
							(end 0.2032 -0.3048)
						)
						(arc
							(start -0.2032 -0.3048)
							(mid -0.275042 -0.275042)
							(end -0.3048 -0.2032)
						)
						(arc
							(start -0.3048 0.2032)
							(mid -0.275042 0.275042)
							(end -0.2032 0.3048)
						)
						(arc
							(start 0.2032 0.3048)
							(mid 0.275042 0.275042)
							(end 0.3048 0.2032)
						)
					)
					(width 0)
					(fill yes)
				)
			)
		)
		(pad "2" smd custom
			(at 0 0.4445)
			(size 0.1524 0.1524)
			(layers "F.Cu" "F.Mask" "F.Paste")
			(net "TPS74801_1V5_SS")
			(options
				(clearance outline)
				(anchor circle)
			)
			(primitives
				(gr_poly
					(pts
						(arc
							(start 0.3048 -0.2032)
							(mid 0.275042 -0.275042)
							(end 0.2032 -0.3048)
						)
						(arc
							(start -0.2032 -0.3048)
							(mid -0.275042 -0.275042)
							(end -0.3048 -0.2032)
						)
						(arc
							(start -0.3048 0.2032)
							(mid -0.275042 0.275042)
							(end -0.2032 0.3048)
						)
						(arc
							(start 0.2032 0.3048)
							(mid 0.275042 0.275042)
							(end 0.3048 0.2032)
						)
					)
					(width 0)
					(fill yes)
				)
			)
		)
	)
	(footprint ""
		(layer "F.Cu")
		(at 124.862844 -9.628378 90)
		(property "Reference" "C130"
			(at 0 0 90)
			(layer "F.SilkS")
			(hide yes)
			(effects
				(font
					(size 1.27 1.27)
				)
			)
		)
		(property "Value" "SCD1U16V2KX-3GP"
			(at 1.1811 -2.7051 90)
			(unlocked yes)
			(layer "F.Fab")
			(hide yes)
			(effects
				(font
					(size 1.016 1.016)
					(thickness 0.1524)
				)
			)
		)
		(property "Device Type" "C402H22"
			(at 1.1811 -4.2291 90)
			(unlocked yes)
			(layer "F.Fab")
			(hide yes)
			(effects
				(font
					(size 1.016 1.016)
					(thickness 0.1524)
				)
			)
		)
		(duplicate_pad_numbers_are_jumpers no)
		(fp_rect
			(start -0.4318 0.9525)
			(end 0.4318 -0.9525)
			(stroke
				(width 0)
				(type default)
			)
			(fill no)
			(layer "F.CrtYd")
		)
		(fp_rect
			(start -0.4318 0.9525)
			(end 0.4318 -0.9525)
			(stroke
				(width 0)
				(type default)
			)
			(fill no)
			(layer "F.Fab")
		)
		(pad "1" smd custom
			(at 0 -0.4445 90)
			(size 0.1524 0.1524)
			(layers "F.Cu" "F.Mask" "F.Paste")
			(net "MB0_CM_VOUT_R")
			(options
				(clearance outline)
				(anchor circle)
			)
			(primitives
				(gr_poly
					(pts
						(arc
							(start 0.3048 -0.2032)
							(mid 0.275042 -0.275042)
							(end 0.2032 -0.3048)
						)
						(arc
							(start -0.2032 -0.3048)
							(mid -0.275042 -0.275042)
							(end -0.3048 -0.2032)
						)
						(arc
							(start -0.3048 0.2032)
							(mid -0.275042 0.275042)
							(end -0.2032 0.3048)
						)
						(arc
							(start 0.2032 0.3048)
							(mid 0.275042 0.275042)
							(end 0.3048 0.2032)
						)
					)
					(width 0)
					(fill yes)
				)
			)
		)
		(pad "2" smd custom
			(at 0 0.4445 90)
			(size 0.1524 0.1524)
			(layers "F.Cu" "F.Mask" "F.Paste")
			(net "AGND_CURRENT_MON")
			(options
				(clearance outline)
				(anchor circle)
			)
			(primitives
				(gr_poly
					(pts
						(arc
							(start 0.3048 -0.2032)
							(mid 0.275042 -0.275042)
							(end 0.2032 -0.3048)
						)
						(arc
							(start -0.2032 -0.3048)
							(mid -0.275042 -0.275042)
							(end -0.3048 -0.2032)
						)
						(arc
							(start -0.3048 0.2032)
							(mid -0.275042 0.275042)
							(end -0.2032 0.3048)
						)
						(arc
							(start 0.2032 0.3048)
							(mid 0.275042 0.275042)
							(end 0.3048 0.2032)
						)
					)
					(width 0)
					(fill yes)
				)
			)
		)
	)
	(footprint ""
		(layer "F.Cu")
		(at 205.867 -49.9618)
		(property "Reference" "TP136"
			(at 0 0 0)
			(layer "F.SilkS")
			(hide yes)
			(effects
				(font
					(size 1.27 1.27)
				)
			)
		)
		(property "Value" "TPAD28-2-GP"
			(at -0.0127 -1.6637 0)
			(unlocked yes)
			(layer "F.Fab")
			(hide yes)
			(effects
				(font
					(size 1.016 1.016)
					(thickness 0.1524)
				)
			)
		)
		(property "Device Type" "TPAD28"
			(at -0.0127 -3.1877 0)
			(unlocked yes)
			(layer "F.Fab")
			(hide yes)
			(effects
				(font
					(size 1.016 1.016)
					(thickness 0.1524)
				)
			)
		)
		(duplicate_pad_numbers_are_jumpers no)
		(fp_poly
			(pts
				(arc
					(start 0.3556 0)
					(mid -0.3556 0)
					(end 0.3556 0)
				)
			)
			(stroke
				(width 0)
				(type default)
			)
			(fill no)
			(layer "F.CrtYd")
		)
		(fp_poly
			(pts
				(arc
					(start 0.6096 0)
					(mid -0.6096 0)
					(end 0.6096 0)
				)
			)
			(stroke
				(width 0)
				(type default)
			)
			(fill no)
			(layer "F.Fab")
		)
		(pad "1" smd circle
			(at 0 0)
			(size 0.7112 0.7112)
			(layers "F.Cu" "F.Mask" "F.Paste")
			(net "ICE0_TMS")
		)
	)
	(footprint ""
		(layer "F.Cu")
		(at 76.385928 -146.839432 90)
		(property "Reference" "R617"
			(at 0 0 90)
			(layer "F.SilkS")
			(hide yes)
			(effects
				(font
					(size 1.27 1.27)
				)
			)
		)
		(property "Value" "0R2J-2-GP"
			(at 0.064008 -3.993896 90)
			(unlocked yes)
			(layer "F.Fab")
			(hide yes)
			(effects
				(font
					(size 1.016 1.016)
					(thickness 0.1524)
				)
			)
		)
		(property "Device Type" "R402H16"
			(at 0.064008 -5.517896 90)
			(unlocked yes)
			(layer "F.Fab")
			(hide yes)
			(effects
				(font
					(size 1.016 1.016)
					(thickness 0.1524)
				)
			)
		)
		(duplicate_pad_numbers_are_jumpers no)
		(fp_line
			(start 0.508 -0.9398)
			(end -0.508 -0.9398)
			(stroke
				(width 0.1524)
				(type default)
			)
			(layer "F.SilkS")
		)
		(fp_line
			(start -0.508 -0.9398)
			(end -0.508 0.9398)
			(stroke
				(width 0.1524)
				(type default)
			)
			(layer "F.SilkS")
		)
		(fp_rect
			(start -0.508 0.9398)
			(end 0.508 -0.9398)
			(stroke
				(width 0)
				(type default)
			)
			(fill no)
			(layer "F.CrtYd")
		)
		(fp_rect
			(start -0.508 0.9398)
			(end 0.508 -0.9398)
			(stroke
				(width 0)
				(type default)
			)
			(fill no)
			(layer "F.Fab")
		)
		(pad "1" smd custom
			(at 0 -0.4445 90)
			(size 0.1397 0.1397)
			(layers "F.Cu" "F.Mask" "F.Paste")
			(net "I2C_DPB_SDA")
			(options
				(clearance outline)
				(anchor circle)
			)
			(primitives
				(gr_poly
					(pts
						(arc
							(start -0.1778 -0.2794)
							(mid -0.249642 -0.249642)
							(end -0.2794 -0.1778)
						)
						(arc
							(start -0.2794 0.1778)
							(mid -0.249642 0.249642)
							(end -0.1778 0.2794)
						)
						(arc
							(start 0.1778 0.2794)
							(mid 0.249642 0.249642)
							(end 0.2794 0.1778)
						)
						(arc
							(start 0.2794 -0.1778)
							(mid 0.249642 -0.249642)
							(end 0.1778 -0.2794)
						)
					)
					(width 0)
					(fill yes)
				)
			)
		)
		(pad "2" smd custom
			(at 0 0.4445 90)
			(size 0.1397 0.1397)
			(layers "F.Cu" "F.Mask" "F.Paste")
			(net "I2C_DPB_SDA_R")
			(options
				(clearance outline)
				(anchor circle)
			)
			(primitives
				(gr_poly
					(pts
						(arc
							(start -0.1778 -0.2794)
							(mid -0.249642 -0.249642)
							(end -0.2794 -0.1778)
						)
						(arc
							(start -0.2794 0.1778)
							(mid -0.249642 0.249642)
							(end -0.1778 0.2794)
						)
						(arc
							(start 0.1778 0.2794)
							(mid 0.249642 0.249642)
							(end 0.2794 0.1778)
						)
						(arc
							(start 0.2794 -0.1778)
							(mid 0.249642 -0.249642)
							(end 0.1778 -0.2794)
						)
					)
					(width 0)
					(fill yes)
				)
			)
		)
	)
)
